(kicad_pcb
	(version 20260206)
	(generator "pcbnew")
	(generator_version "10.0")
	(general
		(thickness 1.6)
		(legacy_teardrops no)
	)
	(paper "A4")
	(title_block
		(title "Bryce Canyon_Front Panel_16369-1_OCP.brd")
		(comment 1 "Bryce Canyon / footprints 50-55 of 154")
	)
	(layers
		(0 "F.Cu" signal "TOP")
		(4 "In1.Cu" signal "L2GND")
		(6 "In2.Cu" signal "L3VCC")
		(2 "B.Cu" signal "BOTTOM")
		(9 "F.Adhes" user "F.Adhesive")
		(11 "B.Adhes" user "B.Adhesive")
		(13 "F.Paste" user "Package Geometry/Pastemask Top")
		(15 "B.Paste" user "Package Geometry/Pastemask Bottom")
		(5 "F.SilkS" user "Ref Des/Silkscreen Top")
		(7 "B.SilkS" user "Ref Des/Silkscreen Bottom")
		(1 "F.Mask" user "Board Geometry/Soldermask Top")
		(3 "B.Mask" user "Board Geometry/Soldermask Bottom")
		(17 "Dwgs.User" user "User.Drawings")
		(19 "Cmts.User" user "User.Comments")
		(21 "Eco1.User" user "User.Eco1")
		(23 "Eco2.User" user "User.Eco2")
		(25 "Edge.Cuts" user "Board Geometry/Outline")
		(27 "Margin" user)
		(31 "F.CrtYd" user "Package Geometry/Place Bound Top")
		(29 "B.CrtYd" user "Package Geometry/Place Bound Bottom")
		(35 "F.Fab" user "Ref Des/Assembly Top")
		(33 "B.Fab" user "Ref Des/Assembly Bottom")
	)
	(footprint ""
		(layer "F.Cu")
		(at 13.97 -28.067 90)
		(property "Reference" "U15"
			(at 0 0 90)
			(layer "F.SilkS")
			(hide yes)
			(effects
				(font
					(size 1.27 1.27)
				)
			)
		)
		(property "Value" "SN74LVC1G08DCKR-GP"
			(at -2.3368 -8.6868 90)
			(unlocked yes)
			(layer "F.Fab")
			(hide yes)
			(effects
				(font
					(size 1.016 1.016)
					(thickness 0.1524)
				)
			)
		)
		(property "Device Type" "SC70-5H44"
			(at -2.3114 -10.414 90)
			(unlocked yes)
			(layer "F.Fab")
			(hide yes)
			(effects
				(font
					(size 1.016 1.016)
					(thickness 0.1524)
				)
			)
		)
		(duplicate_pad_numbers_are_jumpers no)
		(fp_line
			(start 1.3843 -1.8034)
			(end 1.3843 -1.1176)
			(stroke
				(width 0.3302)
				(type default)
			)
			(layer "F.SilkS")
		)
		(fp_line
			(start 0.6604 -1.8034)
			(end 1.3843 -1.8034)
			(stroke
				(width 0.3302)
				(type default)
			)
			(layer "F.SilkS")
		)
		(fp_line
			(start 1.27 -1.7018)
			(end 1.27 1.7018)
			(stroke
				(width 0.1524)
				(type default)
			)
			(layer "F.SilkS")
		)
		(fp_line
			(start -1.27 -1.7018)
			(end 1.27 -1.7018)
			(stroke
				(width 0.1524)
				(type default)
			)
			(layer "F.SilkS")
		)
		(fp_line
			(start 1.27 1.7018)
			(end -1.27 1.7018)
			(stroke
				(width 0.1524)
				(type default)
			)
			(layer "F.SilkS")
		)
		(fp_line
			(start -1.27 1.7018)
			(end -1.27 -1.7018)
			(stroke
				(width 0.1524)
				(type default)
			)
			(layer "F.SilkS")
		)
		(fp_rect
			(start -1.524 1.9558)
			(end 1.524 -1.9558)
			(stroke
				(width 0)
				(type default)
			)
			(fill no)
			(layer "F.CrtYd")
		)
		(fp_poly
			(pts
				(xy -1.524 -1.9558) (xy 1.524 -1.9558) (xy 1.524 1.9558) (xy -1.524 1.9558)
			)
			(stroke
				(width 0)
				(type default)
			)
			(fill no)
			(layer "F.Fab")
		)
		(pad "1" smd rect
			(at 0.65024 -0.8255 90)
			(size 0.4064 1.2192)
			(layers "F.Cu" "F.Mask" "F.Paste")
			(net "SYS_RESET_BTN_A_N_R")
		)
		(pad "2" smd rect
			(at 0 -0.8255 90)
			(size 0.4064 1.2192)
			(layers "F.Cu" "F.Mask" "F.Paste")
			(net "DEBUG_RST_A_BTN_N")
		)
		(pad "3" smd rect
			(at -0.65024 -0.8255 90)
			(size 0.4064 1.2192)
			(layers "F.Cu" "F.Mask" "F.Paste")
			(net "GND")
		)
		(pad "4" smd rect
			(at -0.65024 0.8255 90)
			(size 0.4064 1.2192)
			(layers "F.Cu" "F.Mask" "F.Paste")
			(net "SYS_RESET_BTN_A_N")
		)
		(pad "5" smd rect
			(at 0.65024 0.8255 90)
			(size 0.4064 1.2192)
			(layers "F.Cu" "F.Mask" "F.Paste")
			(net "P3V3_STBY_A")
		)
	)
	(footprint ""
		(layer "F.Cu")
		(at 48.662082 -39.751 -90)
		(property "Reference" "R26"
			(at 0 0 270)
			(layer "F.SilkS")
			(hide yes)
			(effects
				(font
					(size 1.27 1.27)
				)
			)
		)
		(property "Value" "120R3J-2-GP"
			(at -0.0254 -2.5146 270)
			(unlocked yes)
			(layer "F.Fab")
			(hide yes)
			(effects
				(font
					(size 1.016 1.016)
					(thickness 0.1524)
				)
			)
		)
		(property "Device Type" "R603H22"
			(at -0.0254 -4.0386 270)
			(unlocked yes)
			(layer "F.Fab")
			(hide yes)
			(effects
				(font
					(size 1.016 1.016)
					(thickness 0.1524)
				)
			)
		)
		(duplicate_pad_numbers_are_jumpers no)
		(fp_line
			(start -0.4826 0)
			(end -0.2032 0)
			(stroke
				(width 0.2032)
				(type default)
			)
			(layer "F.SilkS")
		)
		(fp_line
			(start 0.2032 0)
			(end 0.4826 0)
			(stroke
				(width 0.2032)
				(type default)
			)
			(layer "F.SilkS")
		)
		(fp_rect
			(start -0.5842 1.3335)
			(end 0.5842 -1.3335)
			(stroke
				(width 0)
				(type default)
			)
			(fill no)
			(layer "F.CrtYd")
		)
		(fp_rect
			(start -0.5842 1.3335)
			(end 0.5842 -1.3335)
			(stroke
				(width 0)
				(type default)
			)
			(fill no)
			(layer "F.Fab")
		)
		(pad "1" smd custom
			(at 0 -0.762 270)
			(size 0.2159 0.2159)
			(layers "F.Cu" "F.Mask" "F.Paste")
			(net "P5V_USB_B")
			(options
				(clearance outline)
				(anchor circle)
			)
			(primitives
				(gr_poly
					(pts
						(arc
							(start -0.3302 -0.4318)
							(mid -0.402042 -0.402042)
							(end -0.4318 -0.3302)
						)
						(arc
							(start -0.4318 0.3302)
							(mid -0.402042 0.402042)
							(end -0.3302 0.4318)
						)
						(arc
							(start 0.3302 0.4318)
							(mid 0.402042 0.402042)
							(end 0.4318 0.3302)
						)
						(arc
							(start 0.4318 -0.3302)
							(mid 0.402042 -0.402042)
							(end 0.3302 -0.4318)
						)
					)
					(width 0)
					(fill yes)
				)
			)
		)
		(pad "2" smd custom
			(at 0 0.762 270)
			(size 0.2159 0.2159)
			(layers "F.Cu" "F.Mask" "F.Paste")
			(net "SYS_FAULT_B_R")
			(options
				(clearance outline)
				(anchor circle)
			)
			(primitives
				(gr_poly
					(pts
						(arc
							(start -0.3302 -0.4318)
							(mid -0.402042 -0.402042)
							(end -0.4318 -0.3302)
						)
						(arc
							(start -0.4318 0.3302)
							(mid -0.402042 0.402042)
							(end -0.3302 0.4318)
						)
						(arc
							(start 0.3302 0.4318)
							(mid 0.402042 0.402042)
							(end 0.4318 0.3302)
						)
						(arc
							(start 0.4318 -0.3302)
							(mid 0.402042 -0.402042)
							(end 0.3302 -0.4318)
						)
					)
					(width 0)
					(fill yes)
				)
			)
		)
	)
	(footprint ""
		(layer "F.Cu")
		(at 45.974 -20.193 -90)
		(property "Reference" "U12"
			(at 0 0 270)
			(layer "F.SilkS")
			(hide yes)
			(effects
				(font
					(size 1.27 1.27)
				)
			)
		)
		(property "Value" "PCA9306DCTT-GP"
			(at 0 -11.6332 270)
			(unlocked yes)
			(layer "F.Fab")
			(hide yes)
			(effects
				(font
					(size 1.016 1.016)
					(thickness 0.1524)
				)
			)
		)
		(property "Device Type" "SSOIC8H52"
			(at 0 -13.1572 270)
			(unlocked yes)
			(layer "F.Fab")
			(hide yes)
			(effects
				(font
					(size 1.016 1.016)
					(thickness 0.1524)
				)
			)
		)
		(duplicate_pad_numbers_are_jumpers no)
		(fp_line
			(start -1.524 0.5842)
			(end -1.524 2.286)
			(stroke
				(width 0.508)
				(type default)
			)
			(layer "F.SilkS")
		)
		(fp_line
			(start 1.0668 0.5842)
			(end -1.524 0.5842)
			(stroke
				(width 0.1524)
				(type default)
			)
			(layer "F.SilkS")
		)
		(fp_line
			(start -1.397 0)
			(end -1.7018 0.3048)
			(stroke
				(width 0.1524)
				(type default)
			)
			(layer "F.SilkS")
		)
		(fp_line
			(start -1.397 0)
			(end -1.7018 -0.3048)
			(stroke
				(width 0.1524)
				(type default)
			)
			(layer "F.SilkS")
		)
		(fp_line
			(start -1.7018 -0.5842)
			(end -1.7018 2.286)
			(stroke
				(width 0.1524)
				(type default)
			)
			(layer "F.SilkS")
		)
		(fp_line
			(start -1.7018 -0.5842)
			(end 1.0668 -0.5842)
			(stroke
				(width 0.1524)
				(type default)
			)
			(layer "F.SilkS")
		)
		(fp_line
			(start 1.0668 -0.5842)
			(end 1.0668 0.5842)
			(stroke
				(width 0.1524)
				(type default)
			)
			(layer "F.SilkS")
		)
		(fp_poly
			(pts
				(xy -1.1684 -0.5842) (xy 1.0668 -0.5842) (xy 1.0668 0.5842) (xy -1.1684 0.5842)
			)
			(stroke
				(width 0)
				(type default)
			)
			(fill yes)
			(layer "F.SilkS")
		)
		(fp_poly
			(pts
				(xy -1.778 2.54) (xy 1.778 2.54) (xy 1.778 -2.54) (xy -1.778 -2.54)
			)
			(stroke
				(width 0)
				(type default)
			)
			(fill no)
			(layer "F.CrtYd")
		)
		(fp_poly
			(pts
				(xy -1.778 -2.54) (xy 1.778 -2.54) (xy 1.778 2.54) (xy -1.778 2.54)
			)
			(stroke
				(width 0)
				(type default)
			)
			(fill no)
			(layer "F.Fab")
		)
		(pad "1" smd rect
			(at -0.97536 1.6256 270)
			(size 0.3556 1.524)
			(layers "F.Cu" "F.Mask" "F.Paste")
			(net "GND")
		)
		(pad "2" smd rect
			(at -0.32512 1.6256 270)
			(size 0.3556 1.524)
			(layers "F.Cu" "F.Mask" "F.Paste")
			(net "P3V3_STBY_B")
		)
		(pad "3" smd rect
			(at 0.32512 1.6256 270)
			(size 0.3556 1.524)
			(layers "F.Cu" "F.Mask" "F.Paste")
			(net "I2C_DEBUG_B_SCL")
		)
		(pad "4" smd rect
			(at 0.97536 1.6256 270)
			(size 0.3556 1.524)
			(layers "F.Cu" "F.Mask" "F.Paste")
			(net "I2C_DEBUG_B_SDA")
		)
		(pad "5" smd rect
			(at 0.97536 -1.6256 270)
			(size 0.3556 1.524)
			(layers "F.Cu" "F.Mask" "F.Paste")
			(net "I2C_DEBUG_B_SDA_L")
		)
		(pad "6" smd rect
			(at 0.32512 -1.6256 270)
			(size 0.3556 1.524)
			(layers "F.Cu" "F.Mask" "F.Paste")
			(net "I2C_DEBUG_B_SCL_L")
		)
		(pad "7" smd rect
			(at -0.32512 -1.6256 270)
			(size 0.3556 1.524)
			(layers "F.Cu" "F.Mask" "F.Paste")
			(net "P3V3_STBY_B")
		)
		(pad "8" smd rect
			(at -0.97536 -1.6256 270)
			(size 0.3556 1.524)
			(layers "F.Cu" "F.Mask" "F.Paste")
			(net "DEBUG_CARD_B_PRSNT")
		)
	)
	(footprint ""
		(layer "F.Cu")
		(at 53.3146 -44.2976)
		(property "Reference" "R39"
			(at 0 0 0)
			(layer "F.SilkS")
			(hide yes)
			(effects
				(font
					(size 1.27 1.27)
				)
			)
		)
		(property "Value" "0R2J-2-GP"
			(at 0.064008 -4.679696 0)
			(unlocked yes)
			(layer "F.Fab")
			(hide yes)
			(effects
				(font
					(size 2.54 2.54)
					(thickness 0.381)
				)
			)
		)
		(property "Device Type" "R402H16"
			(at 0.064008 -6.203696 0)
			(unlocked yes)
			(layer "F.Fab")
			(hide yes)
			(effects
				(font
					(size 2.54 2.54)
					(thickness 0.381)
				)
			)
		)
		(duplicate_pad_numbers_are_jumpers no)
		(fp_line
			(start -0.508 -0.9398)
			(end -0.508 0.9398)
			(stroke
				(width 0.1524)
				(type default)
			)
			(layer "F.SilkS")
		)
		(fp_line
			(start 0.508 -0.9398)
			(end -0.508 -0.9398)
			(stroke
				(width 0.1524)
				(type default)
			)
			(layer "F.SilkS")
		)
		(fp_rect
			(start -0.508 0.9398)
			(end 0.508 -0.9398)
			(stroke
				(width 0)
				(type default)
			)
			(fill no)
			(layer "F.CrtYd")
		)
		(fp_rect
			(start -0.508 0.9398)
			(end 0.508 -0.9398)
			(stroke
				(width 0)
				(type default)
			)
			(fill no)
			(layer "F.Fab")
		)
		(pad "1" smd custom
			(at 0 -0.4445)
			(size 0.1397 0.1397)
			(layers "F.Cu" "F.Mask" "F.Paste")
			(net "TEMP_2_SDA")
			(options
				(clearance outline)
				(anchor circle)
			)
			(primitives
				(gr_poly
					(pts
						(arc
							(start -0.1778 -0.2794)
							(mid -0.249642 -0.249642)
							(end -0.2794 -0.1778)
						)
						(arc
							(start -0.2794 0.1778)
							(mid -0.249642 0.249642)
							(end -0.1778 0.2794)
						)
						(arc
							(start 0.1778 0.2794)
							(mid 0.249642 0.249642)
							(end 0.2794 0.1778)
						)
						(arc
							(start 0.2794 -0.1778)
							(mid 0.249642 -0.249642)
							(end 0.1778 -0.2794)
						)
					)
					(width 0)
					(fill yes)
				)
			)
		)
		(pad "2" smd custom
			(at 0 0.4445)
			(size 0.1397 0.1397)
			(layers "F.Cu" "F.Mask" "F.Paste")
			(net "I2C_DPB_B_SDA")
			(options
				(clearance outline)
				(anchor circle)
			)
			(primitives
				(gr_poly
					(pts
						(arc
							(start -0.1778 -0.2794)
							(mid -0.249642 -0.249642)
							(end -0.2794 -0.1778)
						)
						(arc
							(start -0.2794 0.1778)
							(mid -0.249642 0.249642)
							(end -0.1778 0.2794)
						)
						(arc
							(start 0.1778 0.2794)
							(mid 0.249642 0.249642)
							(end 0.2794 0.1778)
						)
						(arc
							(start 0.2794 -0.1778)
							(mid 0.249642 -0.249642)
							(end 0.1778 -0.2794)
						)
					)
					(width 0)
					(fill yes)
				)
			)
		)
	)
	(footprint ""
		(layer "F.Cu")
		(at 55.2196 -47.0662 -90)
		(property "Reference" "R42"
			(at 0 0 270)
			(layer "F.SilkS")
			(hide yes)
			(effects
				(font
					(size 1.27 1.27)
				)
			)
		)
		(property "Value" "4K7R2F-GP"
			(at 0.064008 -4.679696 270)
			(unlocked yes)
			(layer "F.Fab")
			(hide yes)
			(effects
				(font
					(size 2.54 2.54)
					(thickness 0.381)
				)
			)
		)
		(property "Device Type" "R402H16"
			(at 0.064008 -6.203696 270)
			(unlocked yes)
			(layer "F.Fab")
			(hide yes)
			(effects
				(font
					(size 2.54 2.54)
					(thickness 0.381)
				)
			)
		)
		(duplicate_pad_numbers_are_jumpers no)
		(fp_line
			(start -0.508 -0.9398)
			(end -0.508 0.9398)
			(stroke
				(width 0.1524)
				(type default)
			)
			(layer "F.SilkS")
		)
		(fp_line
			(start 0.508 -0.9398)
			(end -0.508 -0.9398)
			(stroke
				(width 0.1524)
				(type default)
			)
			(layer "F.SilkS")
		)
		(fp_rect
			(start -0.508 0.9398)
			(end 0.508 -0.9398)
			(stroke
				(width 0)
				(type default)
			)
			(fill no)
			(layer "F.CrtYd")
		)
		(fp_rect
			(start -0.508 0.9398)
			(end 0.508 -0.9398)
			(stroke
				(width 0)
				(type default)
			)
			(fill no)
			(layer "F.Fab")
		)
		(pad "1" smd custom
			(at 0 -0.4445 270)
			(size 0.1397 0.1397)
			(layers "F.Cu" "F.Mask" "F.Paste")
			(net "P3V3_STBY_B")
			(options
				(clearance outline)
				(anchor circle)
			)
			(primitives
				(gr_poly
					(pts
						(arc
							(start -0.1778 -0.2794)
							(mid -0.249642 -0.249642)
							(end -0.2794 -0.1778)
						)
						(arc
							(start -0.2794 0.1778)
							(mid -0.249642 0.249642)
							(end -0.1778 0.2794)
						)
						(arc
							(start 0.1778 0.2794)
							(mid 0.249642 0.249642)
							(end 0.2794 0.1778)
						)
						(arc
							(start 0.2794 -0.1778)
							(mid 0.249642 -0.249642)
							(end 0.1778 -0.2794)
						)
					)
					(width 0)
					(fill yes)
				)
			)
		)
		(pad "2" smd custom
			(at 0 0.4445 270)
			(size 0.1397 0.1397)
			(layers "F.Cu" "F.Mask" "F.Paste")
			(net "TEMP_2_A2")
			(options
				(clearance outline)
				(anchor circle)
			)
			(primitives
				(gr_poly
					(pts
						(arc
							(start -0.1778 -0.2794)
							(mid -0.249642 -0.249642)
							(end -0.2794 -0.1778)
						)
						(arc
							(start -0.2794 0.1778)
							(mid -0.249642 0.249642)
							(end -0.1778 0.2794)
						)
						(arc
							(start 0.1778 0.2794)
							(mid 0.249642 0.249642)
							(end 0.2794 0.1778)
						)
						(arc
							(start 0.2794 -0.1778)
							(mid 0.249642 -0.249642)
							(end 0.1778 -0.2794)
						)
					)
					(width 0)
					(fill yes)
				)
			)
		)
	)
	(footprint ""
		(layer "F.Cu")
		(at 46.36008 -70.226174 90)
		(property "Reference" "L3"
			(at 0 0 90)
			(layer "F.SilkS")
			(hide yes)
			(effects
				(font
					(size 1.27 1.27)
				)
			)
		)
		(property "Value" "BLM21PG300SN-2GP"
			(at 0.0254 -6.3754 90)
			(unlocked yes)
			(layer "F.Fab")
			(hide yes)
			(effects
				(font
					(size 2.54 2.54)
					(thickness 0.381)
				)
			)
		)
		(property "Device Type" "L20125H42"
			(at 0.0254 -8.2804 90)
			(unlocked yes)
			(layer "F.Fab")
			(hide yes)
			(effects
				(font
					(size 2.54 2.54)
					(thickness 0.381)
				)
			)
		)
		(duplicate_pad_numbers_are_jumpers no)
		(fp_line
			(start 0.9144 -1.7018)
			(end -0.9144 -1.7018)
			(stroke
				(width 0.1524)
				(type default)
			)
			(layer "F.SilkS")
		)
		(fp_line
			(start -0.9144 -1.7018)
			(end -0.9144 1.7018)
			(stroke
				(width 0.1524)
				(type default)
			)
			(layer "F.SilkS")
		)
		(fp_line
			(start 0.9144 1.7018)
			(end 0.9144 -1.7018)
			(stroke
				(width 0.1524)
				(type default)
			)
			(layer "F.SilkS")
		)
		(fp_line
			(start -0.9144 1.7018)
			(end 0.9144 1.7018)
			(stroke
				(width 0.1524)
				(type default)
			)
			(layer "F.SilkS")
		)
		(fp_rect
			(start -1.0033 1.778)
			(end 1.0033 -1.778)
			(stroke
				(width 0)
				(type default)
			)
			(fill no)
			(layer "F.CrtYd")
		)
		(fp_poly
			(pts
				(xy -1.0033 -1.778) (xy 1.0033 -1.778) (xy 1.0033 1.778) (xy -1.0033 1.778)
			)
			(stroke
				(width 0)
				(type default)
			)
			(fill no)
			(layer "F.Fab")
		)
		(pad "1" smd rect
			(at 0 -0.9652 90)
			(size 1.397 1.143)
			(layers "F.Cu" "F.Mask" "F.Paste")
			(net "P5V_VBUS_B")
		)
		(pad "2" smd rect
			(at 0 0.9652 90)
			(size 1.397 1.143)
			(layers "F.Cu" "F.Mask" "F.Paste")
			(net "P5V_USB_B")
		)
	)
)
